# S9S_MB_2U (Grand Teton) — schematic netlist excerpt (pin names and nets, part order shuffled) for the footprints in the layout excerpt that follows; sources: Cadence DE-HDL packaged netlist, KiCad conversion of 03242023_DA0F0TMBIJ0_F0T_Motherboard_J_brd_V01_OCP.brd

C403  Q_CAP  22UF 4V 20% X6S  pkg C0402  page 74 : A = PVCCD_HV_CPU0 ; B = GND
C258  Q_CAP  10UF 6.3V 20% X6S  pkg C0402  page 77 : A = PVCCIN_CPU1 ; B = GND
PC1233  Q_CAP  10UF 16V 10% X6S  pkg C0805  page 263 : A = SW_P1V8_PCH_AUX_FLT ; B = GND

(kicad_pcb
	(version 20260206)
	(generator "pcbnew")
	(generator_version "10.0")
	(general
		(thickness 1.6)
		(legacy_teardrops no)
	)
	(paper "A4")
	(title_block
		(title "03242023_DA0F0TMBIJ0_F0T_Motherboard_J_brd_V01_OCP.brd")
		(comment 1 "Grand Teton / footprints 450-452 of 6105")
	)
	(layers
		(0 "F.Cu" signal "TOP")
		(4 "In1.Cu" signal "GND")
		(6 "In2.Cu" signal "IN1")
		(8 "In3.Cu" signal "GND1")
		(10 "In4.Cu" signal "IN2")
		(12 "In5.Cu" signal "GND2")
		(14 "In6.Cu" signal "IN3")
		(16 "In7.Cu" signal "GND3")
		(18 "In8.Cu" signal "VCC")
		(20 "In9.Cu" signal "VCC1")
		(22 "In10.Cu" signal "GND4")
		(24 "In11.Cu" signal "IN4")
		(26 "In12.Cu" signal "GND5")
		(28 "In13.Cu" signal "IN5")
		(30 "In14.Cu" signal "GND6")
		(32 "In15.Cu" signal "IN6")
		(34 "In16.Cu" signal "GND7")
		(2 "B.Cu" signal "BOTTOM")
		(9 "F.Adhes" user "F.Adhesive")
		(11 "B.Adhes" user "B.Adhesive")
		(13 "F.Paste" user "Package Geometry/Pastemask Top")
		(15 "B.Paste" user "Package Geometry/Pastemask Bottom")
		(5 "F.SilkS" user "Ref Des/Silkscreen Top")
		(7 "B.SilkS" user "Ref Des/Silkscreen Bottom")
		(1 "F.Mask" user "Board Geometry/Soldermask Top")
		(3 "B.Mask" user "Board Geometry/Soldermask Bottom")
		(17 "Dwgs.User" user "User.Drawings")
		(19 "Cmts.User" user "User.Comments")
		(21 "Eco1.User" user "User.Eco1")
		(23 "Eco2.User" user "User.Eco2")
		(25 "Edge.Cuts" user "Board Geometry/Outline")
		(27 "Margin" user)
		(31 "F.CrtYd" user "Package Geometry/Place Bound Top")
		(29 "B.CrtYd" user "Package Geometry/Place Bound Bottom")
		(35 "F.Fab" user "Ref Des/Assembly Top")
		(33 "B.Fab" user "Ref Des/Assembly Bottom")
	)
	(footprint ""
		(layer "F.Cu")
		(at 367.44783 -245.634002 -90)
		(property "Reference" "C403"
			(at 0 0 270)
			(layer "F.SilkS")
			(hide yes)
			(effects
				(font
					(size 1.27 1.27)
				)
			)
		)
		(property "Value" ""
			(at 0 0 270)
			(layer "F.Fab")
			(effects
				(font
					(size 1.27 1.27)
				)
			)
		)
		(duplicate_pad_numbers_are_jumpers no)
		(fp_line
			(start -0.7874 0.4064)
			(end -0.7874 -0.4064)
			(stroke
				(width 0.1524)
				(type default)
			)
			(layer "F.SilkS")
		)
		(fp_line
			(start 0.7874 0.4064)
			(end -0.7874 0.4064)
			(stroke
				(width 0.1524)
				(type default)
			)
			(layer "F.SilkS")
		)
		(fp_line
			(start -0.7874 -0.4064)
			(end 0.7874 -0.4064)
			(stroke
				(width 0.1524)
				(type default)
			)
			(layer "F.SilkS")
		)
		(fp_line
			(start 0.7874 -0.4064)
			(end 0.7874 0.4064)
			(stroke
				(width 0.1524)
				(type default)
			)
			(layer "F.SilkS")
		)
		(fp_line
			(start -0.67945 0.3048)
			(end -0.67945 -0.305054)
			(stroke
				(width 0.1)
				(type default)
			)
			(layer "F.Fab")
		)
		(fp_line
			(start -0.12065 0.3048)
			(end -0.67945 0.3048)
			(stroke
				(width 0.1)
				(type default)
			)
			(layer "F.Fab")
		)
		(fp_line
			(start 0.120396 0.3048)
			(end 0.120396 0.2794)
			(stroke
				(width 0.1)
				(type default)
			)
			(layer "F.Fab")
		)
		(fp_line
			(start 0.67945 0.3048)
			(end 0.120396 0.3048)
			(stroke
				(width 0.1)
				(type default)
			)
			(layer "F.Fab")
		)
		(fp_line
			(start -0.12065 0.2794)
			(end -0.12065 0.3048)
			(stroke
				(width 0.1)
				(type default)
			)
			(layer "F.Fab")
		)
		(fp_line
			(start 0.120396 0.2794)
			(end -0.12065 0.2794)
			(stroke
				(width 0.1)
				(type default)
			)
			(layer "F.Fab")
		)
		(fp_line
			(start -0.12065 -0.2794)
			(end 0.12065 -0.2794)
			(stroke
				(width 0.1)
				(type default)
			)
			(layer "F.Fab")
		)
		(fp_line
			(start 0.12065 -0.2794)
			(end 0.12065 -0.3048)
			(stroke
				(width 0.1)
				(type default)
			)
			(layer "F.Fab")
		)
		(fp_line
			(start 0.12065 -0.3048)
			(end 0.67945 -0.3048)
			(stroke
				(width 0.1)
				(type default)
			)
			(layer "F.Fab")
		)
		(fp_line
			(start 0.67945 -0.3048)
			(end 0.67945 0.3048)
			(stroke
				(width 0.1)
				(type default)
			)
			(layer "F.Fab")
		)
		(fp_line
			(start -0.67945 -0.305054)
			(end -0.12065 -0.305054)
			(stroke
				(width 0.1)
				(type default)
			)
			(layer "F.Fab")
		)
		(fp_line
			(start -0.12065 -0.305054)
			(end -0.12065 -0.2794)
			(stroke
				(width 0.1)
				(type default)
			)
			(layer "F.Fab")
		)
		(pad "1" smd circle
			(at -0.40005 0 270)
			(size 0 0)
			(layers "F.Cu" "F.Mask" "F.Paste")
			(net "PVCCD_HV_CPU0")
		)
		(pad "2" smd circle
			(at 0.40005 0 270)
			(size 0 0)
			(layers "F.Cu" "F.Mask" "F.Paste")
			(net "GND")
		)
	)
	(footprint ""
		(layer "F.Cu")
		(at 388.014972 -76.171044 90)
		(property "Reference" "PC1233"
			(at 0 0 90)
			(layer "F.SilkS")
			(hide yes)
			(effects
				(font
					(size 1.27 1.27)
				)
			)
		)
		(property "Value" ""
			(at 0 0 90)
			(layer "F.Fab")
			(effects
				(font
					(size 1.27 1.27)
				)
			)
		)
		(duplicate_pad_numbers_are_jumpers no)
		(fp_line
			(start 1.524 -0.762)
			(end 1.524 0.762)
			(stroke
				(width 0.1524)
				(type default)
			)
			(layer "F.SilkS")
		)
		(fp_line
			(start -1.524 -0.762)
			(end 1.524 -0.762)
			(stroke
				(width 0.1524)
				(type default)
			)
			(layer "F.SilkS")
		)
		(fp_line
			(start 1.524 0.762)
			(end -1.524 0.762)
			(stroke
				(width 0.1524)
				(type default)
			)
			(layer "F.SilkS")
		)
		(fp_line
			(start -1.524 0.762)
			(end -1.524 -0.762)
			(stroke
				(width 0.1524)
				(type default)
			)
			(layer "F.SilkS")
		)
		(fp_line
			(start 1.1049 -0.724916)
			(end -1.1049 -0.724916)
			(stroke
				(width 0.1)
				(type default)
			)
			(layer "F.Fab")
		)
		(fp_line
			(start -1.1049 -0.724916)
			(end -1.1049 0.724916)
			(stroke
				(width 0.1)
				(type default)
			)
			(layer "F.Fab")
		)
		(fp_line
			(start 1.1049 0.724916)
			(end 1.1049 -0.724916)
			(stroke
				(width 0.1)
				(type default)
			)
			(layer "F.Fab")
		)
		(fp_line
			(start -1.1049 0.724916)
			(end 1.1049 0.724916)
			(stroke
				(width 0.1)
				(type default)
			)
			(layer "F.Fab")
		)
		(pad "1" smd rect
			(at -0.889 0 270)
			(size 1.016 1.27)
			(layers "F.Cu" "F.Mask" "F.Paste")
			(net "SW_P1V8_PCH_AUX_FLT")
		)
		(pad "2" smd rect
			(at 0.889 0 270)
			(size 1.016 1.27)
			(layers "F.Cu" "F.Mask" "F.Paste")
			(net "GND")
		)
	)
	(footprint ""
		(layer "F.Cu")
		(at 119.508016 -251.375672 90)
		(property "Reference" "C258"
			(at 0 0 90)
			(layer "F.SilkS")
			(hide yes)
			(effects
				(font
					(size 1.27 1.27)
				)
			)
		)
		(property "Value" ""
			(at 0 0 90)
			(layer "F.Fab")
			(effects
				(font
					(size 1.27 1.27)
				)
			)
		)
		(duplicate_pad_numbers_are_jumpers no)
		(fp_line
			(start 0.7874 -0.4064)
			(end 0.7874 0.4064)
			(stroke
				(width 0.1524)
				(type default)
			)
			(layer "F.SilkS")
		)
		(fp_line
			(start -0.7874 -0.4064)
			(end 0.7874 -0.4064)
			(stroke
				(width 0.1524)
				(type default)
			)
			(layer "F.SilkS")
		)
		(fp_line
			(start 0.7874 0.4064)
			(end -0.7874 0.4064)
			(stroke
				(width 0.1524)
				(type default)
			)
			(layer "F.SilkS")
		)
		(fp_line
			(start -0.7874 0.4064)
			(end -0.7874 -0.4064)
			(stroke
				(width 0.1524)
				(type default)
			)
			(layer "F.SilkS")
		)
		(fp_line
			(start -0.12065 -0.305054)
			(end -0.12065 -0.2794)
			(stroke
				(width 0.1)
				(type default)
			)
			(layer "F.Fab")
		)
		(fp_line
			(start -0.67945 -0.305054)
			(end -0.12065 -0.305054)
			(stroke
				(width 0.1)
				(type default)
			)
			(layer "F.Fab")
		)
		(fp_line
			(start 0.67945 -0.3048)
			(end 0.67945 0.3048)
			(stroke
				(width 0.1)
				(type default)
			)
			(layer "F.Fab")
		)
		(fp_line
			(start 0.12065 -0.3048)
			(end 0.67945 -0.3048)
			(stroke
				(width 0.1)
				(type default)
			)
			(layer "F.Fab")
		)
		(fp_line
			(start 0.12065 -0.2794)
			(end 0.12065 -0.3048)
			(stroke
				(width 0.1)
				(type default)
			)
			(layer "F.Fab")
		)
		(fp_line
			(start -0.12065 -0.2794)
			(end 0.12065 -0.2794)
			(stroke
				(width 0.1)
				(type default)
			)
			(layer "F.Fab")
		)
		(fp_line
			(start 0.120396 0.2794)
			(end -0.12065 0.2794)
			(stroke
				(width 0.1)
				(type default)
			)
			(layer "F.Fab")
		)
		(fp_line
			(start -0.12065 0.2794)
			(end -0.12065 0.3048)
			(stroke
				(width 0.1)
				(type default)
			)
			(layer "F.Fab")
		)
		(fp_line
			(start 0.67945 0.3048)
			(end 0.120396 0.3048)
			(stroke
				(width 0.1)
				(type default)
			)
			(layer "F.Fab")
		)
		(fp_line
			(start 0.120396 0.3048)
			(end 0.120396 0.2794)
			(stroke
				(width 0.1)
				(type default)
			)
			(layer "F.Fab")
		)
		(fp_line
			(start -0.12065 0.3048)
			(end -0.67945 0.3048)
			(stroke
				(width 0.1)
				(type default)
			)
			(layer "F.Fab")
		)
		(fp_line
			(start -0.67945 0.3048)
			(end -0.67945 -0.305054)
			(stroke
				(width 0.1)
				(type default)
			)
			(layer "F.Fab")
		)
		(pad "1" smd circle
			(at -0.40005 0 90)
			(size 0 0)
			(layers "F.Cu" "F.Mask" "F.Paste")
			(net "PVCCIN_CPU1")
		)
		(pad "2" smd circle
			(at 0.40005 0 90)
			(size 0 0)
			(layers "F.Cu" "F.Mask" "F.Paste")
			(net "GND")
		)
	)
)
